# S9S_MB_2U (Grand Teton) — schematic netlist excerpt (pin names and nets, part order shuffled) for the footprints in the layout excerpt that follows; sources: Cadence DE-HDL packaged netlist, KiCad conversion of 03242023_DA0F0TMBIJ0_F0T_Motherboard_J_brd_V01_OCP.brd

J84  PICOPROBE_BXA  DELTA-L 4.0 EMPTY  pkg TRIANG_LAUNCH_3PXB  page 308
  \1_p\  = DELTA_L_85_10INCH_IN2_DN
  \2_n\  = DELTA_L_85_10INCH_IN2_DP
  \3_g\  = DELTA_L_GND_1

(kicad_pcb
	(version 20260206)
	(generator "pcbnew")
	(generator_version "10.0")
	(general
		(thickness 1.6)
		(legacy_teardrops no)
	)
	(paper "A4")
	(title_block
		(title "03242023_DA0F0TMBIJ0_F0T_Motherboard_J_brd_V01_OCP.brd")
		(comment 1 "Grand Teton / footprints 1198-1198 of 6105")
	)
	(layers
		(0 "F.Cu" signal "TOP")
		(4 "In1.Cu" signal "GND")
		(6 "In2.Cu" signal "IN1")
		(8 "In3.Cu" signal "GND1")
		(10 "In4.Cu" signal "IN2")
		(12 "In5.Cu" signal "GND2")
		(14 "In6.Cu" signal "IN3")
		(16 "In7.Cu" signal "GND3")
		(18 "In8.Cu" signal "VCC")
		(20 "In9.Cu" signal "VCC1")
		(22 "In10.Cu" signal "GND4")
		(24 "In11.Cu" signal "IN4")
		(26 "In12.Cu" signal "GND5")
		(28 "In13.Cu" signal "IN5")
		(30 "In14.Cu" signal "GND6")
		(32 "In15.Cu" signal "IN6")
		(34 "In16.Cu" signal "GND7")
		(2 "B.Cu" signal "BOTTOM")
		(9 "F.Adhes" user "F.Adhesive")
		(11 "B.Adhes" user "B.Adhesive")
		(13 "F.Paste" user "Package Geometry/Pastemask Top")
		(15 "B.Paste" user "Package Geometry/Pastemask Bottom")
		(5 "F.SilkS" user "Ref Des/Silkscreen Top")
		(7 "B.SilkS" user "Ref Des/Silkscreen Bottom")
		(1 "F.Mask" user "Board Geometry/Soldermask Top")
		(3 "B.Mask" user "Board Geometry/Soldermask Bottom")
		(17 "Dwgs.User" user "User.Drawings")
		(19 "Cmts.User" user "User.Comments")
		(21 "Eco1.User" user "User.Eco1")
		(23 "Eco2.User" user "User.Eco2")
		(25 "Edge.Cuts" user "Board Geometry/Outline")
		(27 "Margin" user)
		(31 "F.CrtYd" user "Package Geometry/Place Bound Top")
		(29 "B.CrtYd" user "Package Geometry/Place Bound Bottom")
		(35 "F.Fab" user "Ref Des/Assembly Top")
		(33 "B.Fab" user "Ref Des/Assembly Bottom")
	)
	(footprint ""
		(layer "F.Cu")
		(at 329.240388 5.463794 180)
		(property "Reference" "J84"
			(at -4.415282 -1.140206 90)
			(unlocked yes)
			(layer "F.SilkS")
			(effects
				(font
					(size 0.7874 0.5842)
					(thickness 0.1524)
				)
				(justify left)
			)
		)
		(property "Value" ""
			(at 0 0 180)
			(layer "F.Fab")
			(effects
				(font
					(size 1.27 1.27)
				)
			)
		)
		(duplicate_pad_numbers_are_jumpers no)
		(fp_line
			(start 1.2192 2.1082)
			(end -1.2192 2.1082)
			(stroke
				(width 0.1524)
				(type default)
			)
			(layer "F.SilkS")
		)
		(fp_line
			(start 1.2192 -2.1082)
			(end 1.2192 2.1082)
			(stroke
				(width 0.1524)
				(type default)
			)
			(layer "F.SilkS")
		)
		(fp_line
			(start -1.2192 2.1082)
			(end -1.2192 -2.1082)
			(stroke
				(width 0.1524)
				(type default)
			)
			(layer "F.SilkS")
		)
		(fp_line
			(start -1.2192 -2.1082)
			(end 1.2192 -2.1082)
			(stroke
				(width 0.1524)
				(type default)
			)
			(layer "F.SilkS")
		)
		(pad "" np_thru_hole circle
			(at -2.8829 -1.27 90)
			(size 1.0414 1.0414)
			(drill 1.0414)
			(layers "*.Cu" "*.Mask")
			(clearance 0.381)
			(thermal_gap 0.381)
		)
		(pad "" np_thru_hole circle
			(at -2.8829 1.27 90)
			(size 1.0414 1.0414)
			(drill 1.0414)
			(layers "*.Cu" "*.Mask")
			(clearance 0.381)
			(thermal_gap 0.381)
		)
		(pad "" np_thru_hole circle
			(at 3.4671 -1.27 90)
			(size 1.0414 1.0414)
			(drill 1.0414)
			(layers "*.Cu" "*.Mask")
			(clearance 0.381)
			(thermal_gap 0.381)
		)
		(pad "" np_thru_hole circle
			(at 3.4671 1.27 90)
			(size 1.0414 1.0414)
			(drill 1.0414)
			(layers "*.Cu" "*.Mask")
			(clearance 0.381)
			(thermal_gap 0.381)
		)
		(pad "1" smd rect
			(at 0.8255 -0.249936 90)
			(size 0.3048 0.508)
			(layers "F.Cu" "F.Mask" "F.Paste")
			(net "DELTA_L_85_10INCH_IN2_DN")
		)
		(pad "2" smd rect
			(at 0.8255 0.249936 90)
			(size 0.3048 0.508)
			(layers "F.Cu" "F.Mask" "F.Paste")
			(net "DELTA_L_85_10INCH_IN2_DP")
		)
		(pad "3" smd circle
			(at 0 0 180)
			(size 0 0)
			(layers "F.Cu" "F.Mask" "F.Paste")
			(net "DELTA_L_GND_1")
		)
		(zone
			(layer "F.Cu")
			(hatch none 0.5)
			(connect_pads
				(clearance 0)
			)
			(min_thickness 0.25)
			(keepout
				(tracks not_allowed)
				(vias allowed)
				(pads allowed)
				(copperpour not_allowed)
				(footprints allowed)
			)
			(placement
				(enabled no)
				(sheetname "")
			)
			(fill
				(thermal_gap 0.5)
				(thermal_bridge_width 0.5)
				(island_removal_mode 0)
			)
			(polygon
				(pts
					(xy 328.122788 6.012434) (xy 328.122788 5.91693) (xy 328.719688 5.91693) (xy 328.719688 5.51053)
					(xy 328.122788 5.51053) (xy 328.122788 5.417058) (xy 328.719688 5.417058) (xy 328.719688 5.010658)
					(xy 328.122788 5.010658) (xy 328.122788 4.915154) (xy 328.821288 4.915154) (xy 328.821288 6.012434)
				)
			)
		)
		(zone
			(layers "F.Cu" "B.Cu" "In1.Cu" "In2.Cu" "In3.Cu" "In4.Cu" "In5.Cu" "In6.Cu"
				"In7.Cu" "In8.Cu" "In9.Cu" "In10.Cu" "In11.Cu" "In12.Cu" "In13.Cu" "In14.Cu"
				"In15.Cu" "In16.Cu"
			)
			(hatch none 0.5)
			(connect_pads
				(clearance 0)
			)
			(min_thickness 0.25)
			(keepout
				(tracks not_allowed)
				(vias allowed)
				(pads allowed)
				(copperpour not_allowed)
				(footprints allowed)
			)
			(placement
				(enabled no)
				(sheetname "")
			)
			(fill
				(thermal_gap 0.5)
				(thermal_bridge_width 0.5)
				(island_removal_mode 0)
			)
			(polygon
				(pts
					(arc
						(start 326.700388 4.193794)
						(mid 324.846188 4.193794)
						(end 326.700388 4.193794)
					)
				)
			)
		)
		(zone
			(layers "F.Cu" "B.Cu" "In1.Cu" "In2.Cu" "In3.Cu" "In4.Cu" "In5.Cu" "In6.Cu"
				"In7.Cu" "In8.Cu" "In9.Cu" "In10.Cu" "In11.Cu" "In12.Cu" "In13.Cu" "In14.Cu"
				"In15.Cu" "In16.Cu"
			)
			(hatch none 0.5)
			(connect_pads
				(clearance 0)
			)
			(min_thickness 0.25)
			(keepout
				(tracks not_allowed)
				(vias allowed)
				(pads allowed)
				(copperpour not_allowed)
				(footprints allowed)
			)
			(placement
				(enabled no)
				(sheetname "")
			)
			(fill
				(thermal_gap 0.5)
				(thermal_bridge_width 0.5)
				(island_removal_mode 0)
			)
			(polygon
				(pts
					(arc
						(start 326.700388 6.733794)
						(mid 324.846188 6.733794)
						(end 326.700388 6.733794)
					)
				)
			)
		)
		(zone
			(layers "F.Cu" "B.Cu" "In1.Cu" "In2.Cu" "In3.Cu" "In4.Cu" "In5.Cu" "In6.Cu"
				"In7.Cu" "In8.Cu" "In9.Cu" "In10.Cu" "In11.Cu" "In12.Cu" "In13.Cu" "In14.Cu"
				"In15.Cu" "In16.Cu"
			)
			(hatch none 0.5)
			(connect_pads
				(clearance 0)
			)
			(min_thickness 0.25)
			(keepout
				(tracks not_allowed)
				(vias allowed)
				(pads allowed)
				(copperpour not_allowed)
				(footprints allowed)
			)
			(placement
				(enabled no)
				(sheetname "")
			)
			(fill
				(thermal_gap 0.5)
				(thermal_bridge_width 0.5)
				(island_removal_mode 0)
			)
			(polygon
				(pts
					(arc
						(start 333.050388 4.193794)
						(mid 331.196188 4.193794)
						(end 333.050388 4.193794)
					)
				)
			)
		)
		(zone
			(layers "F.Cu" "B.Cu" "In1.Cu" "In2.Cu" "In3.Cu" "In4.Cu" "In5.Cu" "In6.Cu"
				"In7.Cu" "In8.Cu" "In9.Cu" "In10.Cu" "In11.Cu" "In12.Cu" "In13.Cu" "In14.Cu"
				"In15.Cu" "In16.Cu"
			)
			(hatch none 0.5)
			(connect_pads
				(clearance 0)
			)
			(min_thickness 0.25)
			(keepout
				(tracks not_allowed)
				(vias allowed)
				(pads allowed)
				(copperpour not_allowed)
				(footprints allowed)
			)
			(placement
				(enabled no)
				(sheetname "")
			)
			(fill
				(thermal_gap 0.5)
				(thermal_bridge_width 0.5)
				(island_removal_mode 0)
			)
			(polygon
				(pts
					(arc
						(start 333.050388 6.733794)
						(mid 331.196188 6.733794)
						(end 333.050388 6.733794)
					)
				)
			)
		)
	)
)
